# T6G (Grand Teton) — schematic netlist excerpt (pin names and nets, part order shuffled) for the footprints in the layout excerpt that follows; sources: Cadence DE-HDL packaged netlist, KiCad conversion of 04192023_DAF0TMB3IC0_F0TG_MB_C_brd_V02_OCP.brd

C6056  Q_CAP  0.001UF 50V 10% X7R  pkg C0402  page 177 : A = P1V2_AUX ; B = GND
C2195  Q_CAP  22UF 4V 20% X6S  pkg C0402  page 69 : A = PVDDCR_CPU0_P0 ; B = GND

(kicad_pcb
	(version 20260206)
	(generator "pcbnew")
	(generator_version "10.0")
	(general
		(thickness 1.6)
		(legacy_teardrops no)
	)
	(paper "A4")
	(title_block
		(title "04192023_DAF0TMB3IC0_F0TG_MB_C_brd_V02_OCP.brd")
		(comment 1 "Grand Teton / footprints 6978-6979 of 8354")
	)
	(layers
		(0 "F.Cu" signal "TOP")
		(4 "In1.Cu" signal "GND")
		(6 "In2.Cu" signal "IN1")
		(8 "In3.Cu" signal "GND1")
		(10 "In4.Cu" signal "IN2")
		(12 "In5.Cu" signal "GND2")
		(14 "In6.Cu" signal "IN3")
		(16 "In7.Cu" signal "GND3")
		(18 "In8.Cu" signal "VCC")
		(20 "In9.Cu" signal "VCC1")
		(22 "In10.Cu" signal "GND4")
		(24 "In11.Cu" signal "IN4")
		(26 "In12.Cu" signal "GND5")
		(28 "In13.Cu" signal "IN5")
		(30 "In14.Cu" signal "GND6")
		(32 "In15.Cu" signal "IN6")
		(34 "In16.Cu" signal "GND7")
		(2 "B.Cu" signal "BOTTOM")
		(9 "F.Adhes" user "F.Adhesive")
		(11 "B.Adhes" user "B.Adhesive")
		(13 "F.Paste" user "Package Geometry/Pastemask Top")
		(15 "B.Paste" user "Package Geometry/Pastemask Bottom")
		(5 "F.SilkS" user "Ref Des/Silkscreen Top")
		(7 "B.SilkS" user "Ref Des/Silkscreen Bottom")
		(1 "F.Mask" user "Board Geometry/Soldermask Top")
		(3 "B.Mask" user "Board Geometry/Soldermask Bottom")
		(17 "Dwgs.User" user "User.Drawings")
		(19 "Cmts.User" user "User.Comments")
		(21 "Eco1.User" user "User.Eco1")
		(23 "Eco2.User" user "User.Eco2")
		(25 "Edge.Cuts" user "Board Geometry/Outline")
		(27 "Margin" user)
		(31 "F.CrtYd" user "Package Geometry/Place Bound Top")
		(29 "B.CrtYd" user "Package Geometry/Place Bound Bottom")
		(35 "F.Fab" user "Ref Des/Assembly Top")
		(33 "B.Fab" user "Ref Des/Assembly Bottom")
	)
	(footprint ""
		(layer "B.Cu")
		(at 138.65352 -37.717222 180)
		(property "Reference" "C6056"
			(at 0 0 0)
			(layer "B.SilkS")
			(hide yes)
			(effects
				(font
					(size 1.27 1.27)
				)
				(justify mirror)
			)
		)
		(property "Value" ""
			(at 0 0 0)
			(layer "B.Fab")
			(effects
				(font
					(size 1.27 1.27)
				)
				(justify mirror)
			)
		)
		(duplicate_pad_numbers_are_jumpers no)
		(fp_line
			(start 0.7874 0.4064)
			(end 0.7874 -0.4064)
			(stroke
				(width 0.1524)
				(type default)
			)
			(layer "B.SilkS")
		)
		(fp_line
			(start 0.7874 -0.4064)
			(end -0.7874 -0.4064)
			(stroke
				(width 0.1524)
				(type default)
			)
			(layer "B.SilkS")
		)
		(fp_line
			(start -0.7874 0.4064)
			(end 0.7874 0.4064)
			(stroke
				(width 0.1524)
				(type default)
			)
			(layer "B.SilkS")
		)
		(fp_line
			(start -0.7874 -0.4064)
			(end -0.7874 0.4064)
			(stroke
				(width 0.1524)
				(type default)
			)
			(layer "B.SilkS")
		)
		(fp_line
			(start 0.67945 0.3048)
			(end 0.67945 -0.305054)
			(stroke
				(width 0.1)
				(type default)
			)
			(layer "B.Fab")
		)
		(fp_line
			(start 0.67945 -0.305054)
			(end 0.12065 -0.305054)
			(stroke
				(width 0.1)
				(type default)
			)
			(layer "B.Fab")
		)
		(fp_line
			(start 0.12065 0.3048)
			(end 0.67945 0.3048)
			(stroke
				(width 0.1)
				(type default)
			)
			(layer "B.Fab")
		)
		(fp_line
			(start 0.12065 0.2794)
			(end 0.12065 0.3048)
			(stroke
				(width 0.1)
				(type default)
			)
			(layer "B.Fab")
		)
		(fp_line
			(start 0.12065 -0.2794)
			(end -0.12065 -0.2794)
			(stroke
				(width 0.1)
				(type default)
			)
			(layer "B.Fab")
		)
		(fp_line
			(start 0.12065 -0.305054)
			(end 0.12065 -0.2794)
			(stroke
				(width 0.1)
				(type default)
			)
			(layer "B.Fab")
		)
		(fp_line
			(start -0.120396 0.3048)
			(end -0.120396 0.2794)
			(stroke
				(width 0.1)
				(type default)
			)
			(layer "B.Fab")
		)
		(fp_line
			(start -0.120396 0.2794)
			(end 0.12065 0.2794)
			(stroke
				(width 0.1)
				(type default)
			)
			(layer "B.Fab")
		)
		(fp_line
			(start -0.12065 -0.2794)
			(end -0.12065 -0.3048)
			(stroke
				(width 0.1)
				(type default)
			)
			(layer "B.Fab")
		)
		(fp_line
			(start -0.12065 -0.3048)
			(end -0.67945 -0.3048)
			(stroke
				(width 0.1)
				(type default)
			)
			(layer "B.Fab")
		)
		(fp_line
			(start -0.67945 0.3048)
			(end -0.120396 0.3048)
			(stroke
				(width 0.1)
				(type default)
			)
			(layer "B.Fab")
		)
		(fp_line
			(start -0.67945 -0.3048)
			(end -0.67945 0.3048)
			(stroke
				(width 0.1)
				(type default)
			)
			(layer "B.Fab")
		)
		(pad "1" smd circle
			(at 0.40005 0)
			(size 0 0)
			(layers "B.Cu" "B.Mask" "B.Paste")
			(net "P1V2_AUX")
		)
		(pad "2" smd circle
			(at -0.40005 0)
			(size 0 0)
			(layers "B.Cu" "B.Mask" "B.Paste")
			(net "GND")
		)
	)
	(footprint ""
		(layer "B.Cu")
		(at 370.046758 -248.47931)
		(property "Reference" "C2195"
			(at 0 0 0)
			(layer "B.SilkS")
			(hide yes)
			(effects
				(font
					(size 1.27 1.27)
				)
				(justify mirror)
			)
		)
		(property "Value" ""
			(at 0 0 0)
			(layer "B.Fab")
			(effects
				(font
					(size 1.27 1.27)
				)
				(justify mirror)
			)
		)
		(duplicate_pad_numbers_are_jumpers no)
		(fp_line
			(start -0.7874 -0.4064)
			(end -0.7874 0.4064)
			(stroke
				(width 0.1524)
				(type default)
			)
			(layer "B.SilkS")
		)
		(fp_line
			(start -0.7874 0.4064)
			(end 0.7874 0.4064)
			(stroke
				(width 0.1524)
				(type default)
			)
			(layer "B.SilkS")
		)
		(fp_line
			(start 0.7874 -0.4064)
			(end -0.7874 -0.4064)
			(stroke
				(width 0.1524)
				(type default)
			)
			(layer "B.SilkS")
		)
		(fp_line
			(start 0.7874 0.4064)
			(end 0.7874 -0.4064)
			(stroke
				(width 0.1524)
				(type default)
			)
			(layer "B.SilkS")
		)
		(fp_line
			(start -0.67945 -0.3048)
			(end -0.67945 0.3048)
			(stroke
				(width 0.1)
				(type default)
			)
			(layer "B.Fab")
		)
		(fp_line
			(start -0.67945 0.3048)
			(end -0.120396 0.3048)
			(stroke
				(width 0.1)
				(type default)
			)
			(layer "B.Fab")
		)
		(fp_line
			(start -0.12065 -0.3048)
			(end -0.67945 -0.3048)
			(stroke
				(width 0.1)
				(type default)
			)
			(layer "B.Fab")
		)
		(fp_line
			(start -0.12065 -0.2794)
			(end -0.12065 -0.3048)
			(stroke
				(width 0.1)
				(type default)
			)
			(layer "B.Fab")
		)
		(fp_line
			(start -0.120396 0.2794)
			(end 0.12065 0.2794)
			(stroke
				(width 0.1)
				(type default)
			)
			(layer "B.Fab")
		)
		(fp_line
			(start -0.120396 0.3048)
			(end -0.120396 0.2794)
			(stroke
				(width 0.1)
				(type default)
			)
			(layer "B.Fab")
		)
		(fp_line
			(start 0.12065 -0.305054)
			(end 0.12065 -0.2794)
			(stroke
				(width 0.1)
				(type default)
			)
			(layer "B.Fab")
		)
		(fp_line
			(start 0.12065 -0.2794)
			(end -0.12065 -0.2794)
			(stroke
				(width 0.1)
				(type default)
			)
			(layer "B.Fab")
		)
		(fp_line
			(start 0.12065 0.2794)
			(end 0.12065 0.3048)
			(stroke
				(width 0.1)
				(type default)
			)
			(layer "B.Fab")
		)
		(fp_line
			(start 0.12065 0.3048)
			(end 0.67945 0.3048)
			(stroke
				(width 0.1)
				(type default)
			)
			(layer "B.Fab")
		)
		(fp_line
			(start 0.67945 -0.305054)
			(end 0.12065 -0.305054)
			(stroke
				(width 0.1)
				(type default)
			)
			(layer "B.Fab")
		)
		(fp_line
			(start 0.67945 0.3048)
			(end 0.67945 -0.305054)
			(stroke
				(width 0.1)
				(type default)
			)
			(layer "B.Fab")
		)
		(pad "1" smd circle
			(at 0.40005 0 180)
			(size 0 0)
			(layers "B.Cu" "B.Mask" "B.Paste")
			(net "PVDDCR_CPU0_P0")
		)
		(pad "2" smd circle
			(at -0.40005 0 180)
			(size 0 0)
			(layers "B.Cu" "B.Mask" "B.Paste")
			(net "GND")
		)
	)
)
